# S9S_MB_2U (Grand Teton) — schematic netlist excerpt (pin names and nets, part order shuffled) for the footprints in the layout excerpt that follows; sources: Cadence DE-HDL packaged netlist, KiCad conversion of 03242023_DA0F0TMBIJ0_F0T_Motherboard_J_brd_V01_OCP.brd

R2230  Q_RES  10K 1% CHIP  pkg 0402LF  page 306 : A = P3V3_AUX ; B = A_P12V_STBY_FPH_GATE
R3501  Q_RES  4.7K 5% CHIP  pkg 0402LF  page 238 : A = P3V3_OCP_SFF ; B = SMB_OCP_SFF_3V3AUX_BUF_SDA

(kicad_pcb
	(version 20260206)
	(generator "pcbnew")
	(generator_version "10.0")
	(general
		(thickness 1.6)
		(legacy_teardrops no)
	)
	(paper "A4")
	(title_block
		(title "03242023_DA0F0TMBIJ0_F0T_Motherboard_J_brd_V01_OCP.brd")
		(comment 1 "Grand Teton / footprints 1006-1007 of 6105")
	)
	(layers
		(0 "F.Cu" signal "TOP")
		(4 "In1.Cu" signal "GND")
		(6 "In2.Cu" signal "IN1")
		(8 "In3.Cu" signal "GND1")
		(10 "In4.Cu" signal "IN2")
		(12 "In5.Cu" signal "GND2")
		(14 "In6.Cu" signal "IN3")
		(16 "In7.Cu" signal "GND3")
		(18 "In8.Cu" signal "VCC")
		(20 "In9.Cu" signal "VCC1")
		(22 "In10.Cu" signal "GND4")
		(24 "In11.Cu" signal "IN4")
		(26 "In12.Cu" signal "GND5")
		(28 "In13.Cu" signal "IN5")
		(30 "In14.Cu" signal "GND6")
		(32 "In15.Cu" signal "IN6")
		(34 "In16.Cu" signal "GND7")
		(2 "B.Cu" signal "BOTTOM")
		(9 "F.Adhes" user "F.Adhesive")
		(11 "B.Adhes" user "B.Adhesive")
		(13 "F.Paste" user "Package Geometry/Pastemask Top")
		(15 "B.Paste" user "Package Geometry/Pastemask Bottom")
		(5 "F.SilkS" user "Ref Des/Silkscreen Top")
		(7 "B.SilkS" user "Ref Des/Silkscreen Bottom")
		(1 "F.Mask" user "Board Geometry/Soldermask Top")
		(3 "B.Mask" user "Board Geometry/Soldermask Bottom")
		(17 "Dwgs.User" user "User.Drawings")
		(19 "Cmts.User" user "User.Comments")
		(21 "Eco1.User" user "User.Eco1")
		(23 "Eco2.User" user "User.Eco2")
		(25 "Edge.Cuts" user "Board Geometry/Outline")
		(27 "Margin" user)
		(31 "F.CrtYd" user "Package Geometry/Place Bound Top")
		(29 "B.CrtYd" user "Package Geometry/Place Bound Bottom")
		(35 "F.Fab" user "Ref Des/Assembly Top")
		(33 "B.Fab" user "Ref Des/Assembly Bottom")
	)
	(footprint ""
		(layer "F.Cu")
		(at 220.087444 -102.255574 180)
		(property "Reference" "R2230"
			(at 0 0 180)
			(layer "F.SilkS")
			(hide yes)
			(effects
				(font
					(size 1.27 1.27)
				)
			)
		)
		(property "Value" ""
			(at 0 0 180)
			(layer "F.Fab")
			(effects
				(font
					(size 1.27 1.27)
				)
			)
		)
		(duplicate_pad_numbers_are_jumpers no)
		(fp_line
			(start 0.7874 0.4064)
			(end -0.7874 0.4064)
			(stroke
				(width 0.1524)
				(type default)
			)
			(layer "F.SilkS")
		)
		(fp_line
			(start 0.7874 -0.4064)
			(end 0.7874 0.4064)
			(stroke
				(width 0.1524)
				(type default)
			)
			(layer "F.SilkS")
		)
		(fp_line
			(start -0.7874 0.4064)
			(end -0.7874 -0.4064)
			(stroke
				(width 0.1524)
				(type default)
			)
			(layer "F.SilkS")
		)
		(fp_line
			(start -0.7874 -0.4064)
			(end 0.7874 -0.4064)
			(stroke
				(width 0.1524)
				(type default)
			)
			(layer "F.SilkS")
		)
		(fp_line
			(start 0.67945 0.3048)
			(end 0.120396 0.3048)
			(stroke
				(width 0.1)
				(type default)
			)
			(layer "F.Fab")
		)
		(fp_line
			(start 0.67945 -0.3048)
			(end 0.67945 0.3048)
			(stroke
				(width 0.1)
				(type default)
			)
			(layer "F.Fab")
		)
		(fp_line
			(start 0.12065 -0.2794)
			(end 0.12065 -0.3048)
			(stroke
				(width 0.1)
				(type default)
			)
			(layer "F.Fab")
		)
		(fp_line
			(start 0.12065 -0.3048)
			(end 0.67945 -0.3048)
			(stroke
				(width 0.1)
				(type default)
			)
			(layer "F.Fab")
		)
		(fp_line
			(start 0.120396 0.3048)
			(end 0.120396 0.2794)
			(stroke
				(width 0.1)
				(type default)
			)
			(layer "F.Fab")
		)
		(fp_line
			(start 0.120396 0.2794)
			(end -0.12065 0.2794)
			(stroke
				(width 0.1)
				(type default)
			)
			(layer "F.Fab")
		)
		(fp_line
			(start -0.12065 0.3048)
			(end -0.67945 0.3048)
			(stroke
				(width 0.1)
				(type default)
			)
			(layer "F.Fab")
		)
		(fp_line
			(start -0.12065 0.2794)
			(end -0.12065 0.3048)
			(stroke
				(width 0.1)
				(type default)
			)
			(layer "F.Fab")
		)
		(fp_line
			(start -0.12065 -0.2794)
			(end 0.12065 -0.2794)
			(stroke
				(width 0.1)
				(type default)
			)
			(layer "F.Fab")
		)
		(fp_line
			(start -0.12065 -0.305054)
			(end -0.12065 -0.2794)
			(stroke
				(width 0.1)
				(type default)
			)
			(layer "F.Fab")
		)
		(fp_line
			(start -0.67945 0.3048)
			(end -0.67945 -0.305054)
			(stroke
				(width 0.1)
				(type default)
			)
			(layer "F.Fab")
		)
		(fp_line
			(start -0.67945 -0.305054)
			(end -0.12065 -0.305054)
			(stroke
				(width 0.1)
				(type default)
			)
			(layer "F.Fab")
		)
		(pad "1" smd circle
			(at -0.40005 0 180)
			(size 0 0)
			(layers "F.Cu" "F.Mask" "F.Paste")
			(net "P3V3_AUX")
		)
		(pad "2" smd circle
			(at 0.40005 0 180)
			(size 0 0)
			(layers "F.Cu" "F.Mask" "F.Paste")
			(net "A_P12V_STBY_FPH_GATE")
		)
	)
	(footprint ""
		(layer "F.Cu")
		(at 450.43725 -44.171362 180)
		(property "Reference" "R3501"
			(at 0 0 180)
			(layer "F.SilkS")
			(hide yes)
			(effects
				(font
					(size 1.27 1.27)
				)
			)
		)
		(property "Value" ""
			(at 0 0 180)
			(layer "F.Fab")
			(effects
				(font
					(size 1.27 1.27)
				)
			)
		)
		(duplicate_pad_numbers_are_jumpers no)
		(fp_line
			(start 0.7874 0.4064)
			(end -0.7874 0.4064)
			(stroke
				(width 0.1524)
				(type default)
			)
			(layer "F.SilkS")
		)
		(fp_line
			(start 0.7874 -0.4064)
			(end 0.7874 0.4064)
			(stroke
				(width 0.1524)
				(type default)
			)
			(layer "F.SilkS")
		)
		(fp_line
			(start -0.7874 0.4064)
			(end -0.7874 -0.4064)
			(stroke
				(width 0.1524)
				(type default)
			)
			(layer "F.SilkS")
		)
		(fp_line
			(start -0.7874 -0.4064)
			(end 0.7874 -0.4064)
			(stroke
				(width 0.1524)
				(type default)
			)
			(layer "F.SilkS")
		)
		(fp_line
			(start 0.67945 0.3048)
			(end 0.120396 0.3048)
			(stroke
				(width 0.1)
				(type default)
			)
			(layer "F.Fab")
		)
		(fp_line
			(start 0.67945 -0.3048)
			(end 0.67945 0.3048)
			(stroke
				(width 0.1)
				(type default)
			)
			(layer "F.Fab")
		)
		(fp_line
			(start 0.12065 -0.2794)
			(end 0.12065 -0.3048)
			(stroke
				(width 0.1)
				(type default)
			)
			(layer "F.Fab")
		)
		(fp_line
			(start 0.12065 -0.3048)
			(end 0.67945 -0.3048)
			(stroke
				(width 0.1)
				(type default)
			)
			(layer "F.Fab")
		)
		(fp_line
			(start 0.120396 0.3048)
			(end 0.120396 0.2794)
			(stroke
				(width 0.1)
				(type default)
			)
			(layer "F.Fab")
		)
		(fp_line
			(start 0.120396 0.2794)
			(end -0.12065 0.2794)
			(stroke
				(width 0.1)
				(type default)
			)
			(layer "F.Fab")
		)
		(fp_line
			(start -0.12065 0.3048)
			(end -0.67945 0.3048)
			(stroke
				(width 0.1)
				(type default)
			)
			(layer "F.Fab")
		)
		(fp_line
			(start -0.12065 0.2794)
			(end -0.12065 0.3048)
			(stroke
				(width 0.1)
				(type default)
			)
			(layer "F.Fab")
		)
		(fp_line
			(start -0.12065 -0.2794)
			(end 0.12065 -0.2794)
			(stroke
				(width 0.1)
				(type default)
			)
			(layer "F.Fab")
		)
		(fp_line
			(start -0.12065 -0.305054)
			(end -0.12065 -0.2794)
			(stroke
				(width 0.1)
				(type default)
			)
			(layer "F.Fab")
		)
		(fp_line
			(start -0.67945 0.3048)
			(end -0.67945 -0.305054)
			(stroke
				(width 0.1)
				(type default)
			)
			(layer "F.Fab")
		)
		(fp_line
			(start -0.67945 -0.305054)
			(end -0.12065 -0.305054)
			(stroke
				(width 0.1)
				(type default)
			)
			(layer "F.Fab")
		)
		(pad "1" smd circle
			(at -0.40005 0 180)
			(size 0 0)
			(layers "F.Cu" "F.Mask" "F.Paste")
			(net "P3V3_OCP_SFF")
		)
		(pad "2" smd circle
			(at 0.40005 0 180)
			(size 0 0)
			(layers "F.Cu" "F.Mask" "F.Paste")
			(net "SMB_OCP_SFF_3V3AUX_BUF_SDA")
		)
	)
)
